(kicad_pcb
	(version 20260206)
	(generator "pcbnew")
	(generator_version "10.0")
	(general
		(thickness 1.6)
		(legacy_teardrops no)
	)
	(paper "A4")
	(title_block
		(title "ptb — 12523-1.1018WZS1506.brd")
		(comment 1 "Open Vault / Knox (Wiwynn) / footprints 24-30 of 61")
	)
	(layers
		(0 "F.Cu" signal "TOP")
		(4 "In1.Cu" signal "L2GND")
		(6 "In2.Cu" signal "L3VCC")
		(2 "B.Cu" signal "BOTTOM")
		(9 "F.Adhes" user "F.Adhesive")
		(11 "B.Adhes" user "B.Adhesive")
		(13 "F.Paste" user "Package Geometry/Pastemask Top")
		(15 "B.Paste" user "Package Geometry/Pastemask Bottom")
		(5 "F.SilkS" user "Ref Des/Silkscreen Top")
		(7 "B.SilkS" user "Ref Des/Silkscreen Bottom")
		(1 "F.Mask" user "Board Geometry/Soldermask Top")
		(3 "B.Mask" user "Board Geometry/Soldermask Bottom")
		(17 "Dwgs.User" user "User.Drawings")
		(19 "Cmts.User" user "User.Comments")
		(21 "Eco1.User" user "User.Eco1")
		(23 "Eco2.User" user "User.Eco2")
		(25 "Edge.Cuts" user "Board Geometry/Outline")
		(27 "Margin" user)
		(31 "F.CrtYd" user "Package Geometry/Place Bound Top")
		(29 "B.CrtYd" user "Package Geometry/Place Bound Bottom")
		(35 "F.Fab" user "Ref Des/Assembly Top")
		(33 "B.Fab" user "Ref Des/Assembly Bottom")
	)
	(footprint ""
		(layer "F.Cu")
		(at 134.368794 -75.439778 180)
		(property "Reference" "Q34"
			(at 0 0 180)
			(layer "F.SilkS")
			(hide yes)
			(effects
				(font
					(size 1.27 1.27)
				)
			)
		)
		(property "Value" "2N7002-11-GP"
			(at 0.127 -8.9662 180)
			(unlocked yes)
			(layer "F.Fab")
			(hide yes)
			(effects
				(font
					(size 1.016 1.016)
					(thickness 0.1524)
				)
			)
		)
		(property "Device Type" "SOT23DGS2D4H44"
			(at 0.127 -10.4902 180)
			(unlocked yes)
			(layer "F.Fab")
			(hide yes)
			(effects
				(font
					(size 1.016 1.016)
					(thickness 0.1524)
				)
			)
		)
		(duplicate_pad_numbers_are_jumpers no)
		(fp_line
			(start 1.651 1.778)
			(end 1.651 -1.778)
			(stroke
				(width 0.1524)
				(type default)
			)
			(layer "F.SilkS")
		)
		(fp_line
			(start 1.651 -1.778)
			(end -1.651 -1.778)
			(stroke
				(width 0.1524)
				(type default)
			)
			(layer "F.SilkS")
		)
		(fp_line
			(start -1.651 1.778)
			(end 1.651 1.778)
			(stroke
				(width 0.1524)
				(type default)
			)
			(layer "F.SilkS")
		)
		(fp_line
			(start -1.651 -1.778)
			(end -1.651 1.778)
			(stroke
				(width 0.1524)
				(type default)
			)
			(layer "F.SilkS")
		)
		(fp_poly
			(pts
				(xy -1.778 1.8796) (xy -1.778 -1.8796) (xy 1.778 -1.8796) (xy 1.778 1.8796)
			)
			(stroke
				(width 0)
				(type default)
			)
			(fill no)
			(layer "F.CrtYd")
		)
		(fp_poly
			(pts
				(xy -1.778 1.8796) (xy -1.778 -1.8796) (xy 1.778 -1.8796) (xy 1.778 1.8796)
			)
			(stroke
				(width 0)
				(type default)
			)
			(fill no)
			(layer "F.Fab")
		)
		(pad "D" smd custom
			(at 0 -0.9525 180)
			(size 0.1905 0.1905)
			(layers "F.Cu" "F.Mask" "F.Paste")
			(net "SELF_TRAY_PRESENT")
			(options
				(clearance outline)
				(anchor circle)
			)
			(primitives
				(gr_poly
					(pts
						(arc
							(start -0.1778 0.5715)
							(mid -0.321484 0.511984)
							(end -0.381 0.3683)
						)
						(arc
							(start -0.381 -0.3683)
							(mid -0.321484 -0.511984)
							(end -0.1778 -0.5715)
						)
						(arc
							(start 0.1778 -0.5715)
							(mid 0.321484 -0.511984)
							(end 0.381 -0.3683)
						)
						(arc
							(start 0.381 0.3683)
							(mid 0.321484 0.511984)
							(end 0.1778 0.5715)
						)
					)
					(width 0)
					(fill yes)
				)
			)
		)
		(pad "G" smd custom
			(at -0.98425 0.9525 180)
			(size 0.1905 0.1905)
			(layers "F.Cu" "F.Mask" "F.Paste")
			(net "TRAY_MOSFET_G")
			(options
				(clearance outline)
				(anchor circle)
			)
			(primitives
				(gr_poly
					(pts
						(arc
							(start -0.1778 0.5715)
							(mid -0.321484 0.511984)
							(end -0.381 0.3683)
						)
						(arc
							(start -0.381 -0.3683)
							(mid -0.321484 -0.511984)
							(end -0.1778 -0.5715)
						)
						(arc
							(start 0.1778 -0.5715)
							(mid 0.321484 -0.511984)
							(end 0.381 -0.3683)
						)
						(arc
							(start 0.381 0.3683)
							(mid 0.321484 0.511984)
							(end 0.1778 0.5715)
						)
					)
					(width 0)
					(fill yes)
				)
			)
		)
		(pad "S" smd custom
			(at 0.98425 0.9525 180)
			(size 0.1905 0.1905)
			(layers "F.Cu" "F.Mask" "F.Paste")
			(net "GND")
			(options
				(clearance outline)
				(anchor circle)
			)
			(primitives
				(gr_poly
					(pts
						(arc
							(start -0.1778 0.5715)
							(mid -0.321484 0.511984)
							(end -0.381 0.3683)
						)
						(arc
							(start -0.381 -0.3683)
							(mid -0.321484 -0.511984)
							(end -0.1778 -0.5715)
						)
						(arc
							(start 0.1778 -0.5715)
							(mid 0.321484 -0.511984)
							(end 0.381 -0.3683)
						)
						(arc
							(start 0.381 0.3683)
							(mid 0.321484 0.511984)
							(end 0.1778 0.5715)
						)
					)
					(width 0)
					(fill yes)
				)
			)
		)
	)
	(footprint ""
		(layer "F.Cu")
		(at 156.972 -18.923)
		(property "Reference" "R483"
			(at 0 0 0)
			(layer "F.SilkS")
			(hide yes)
			(effects
				(font
					(size 1.27 1.27)
				)
			)
		)
		(property "Value" "2KR3F-L-GP"
			(at -0.0254 -2.5146 0)
			(unlocked yes)
			(layer "F.Fab")
			(hide yes)
			(effects
				(font
					(size 1.016 1.016)
					(thickness 0.1524)
				)
			)
		)
		(property "Device Type" "R603H22"
			(at -0.0254 -4.0386 0)
			(unlocked yes)
			(layer "F.Fab")
			(hide yes)
			(effects
				(font
					(size 1.016 1.016)
					(thickness 0.1524)
				)
			)
		)
		(duplicate_pad_numbers_are_jumpers no)
		(fp_line
			(start -0.4826 0)
			(end -0.2032 0)
			(stroke
				(width 0.2032)
				(type default)
			)
			(layer "F.SilkS")
		)
		(fp_line
			(start 0.2032 0)
			(end 0.4826 0)
			(stroke
				(width 0.2032)
				(type default)
			)
			(layer "F.SilkS")
		)
		(fp_rect
			(start -0.5842 1.3335)
			(end 0.5842 -1.3335)
			(stroke
				(width 0)
				(type default)
			)
			(fill no)
			(layer "F.CrtYd")
		)
		(fp_rect
			(start -0.5842 1.3335)
			(end 0.5842 -1.3335)
			(stroke
				(width 0)
				(type default)
			)
			(fill no)
			(layer "F.Fab")
		)
		(pad "1" smd custom
			(at 0 -0.762)
			(size 0.2159 0.2159)
			(layers "F.Cu" "F.Mask" "F.Paste")
			(net "P12V")
			(options
				(clearance outline)
				(anchor circle)
			)
			(primitives
				(gr_poly
					(pts
						(arc
							(start -0.3302 -0.4318)
							(mid -0.402042 -0.402042)
							(end -0.4318 -0.3302)
						)
						(arc
							(start -0.4318 0.3302)
							(mid -0.402042 0.402042)
							(end -0.3302 0.4318)
						)
						(arc
							(start 0.3302 0.4318)
							(mid 0.402042 0.402042)
							(end 0.4318 0.3302)
						)
						(arc
							(start 0.4318 -0.3302)
							(mid 0.402042 -0.402042)
							(end 0.3302 -0.4318)
						)
					)
					(width 0)
					(fill yes)
				)
			)
		)
		(pad "2" smd custom
			(at 0 0.762)
			(size 0.2159 0.2159)
			(layers "F.Cu" "F.Mask" "F.Paste")
			(net "TPS2490_LED")
			(options
				(clearance outline)
				(anchor circle)
			)
			(primitives
				(gr_poly
					(pts
						(arc
							(start -0.3302 -0.4318)
							(mid -0.402042 -0.402042)
							(end -0.4318 -0.3302)
						)
						(arc
							(start -0.4318 0.3302)
							(mid -0.402042 0.402042)
							(end -0.3302 0.4318)
						)
						(arc
							(start 0.3302 0.4318)
							(mid 0.402042 0.402042)
							(end 0.4318 0.3302)
						)
						(arc
							(start 0.4318 -0.3302)
							(mid 0.402042 -0.402042)
							(end 0.3302 -0.4318)
						)
					)
					(width 0)
					(fill yes)
				)
			)
		)
	)
	(footprint ""
		(layer "F.Cu")
		(at 17.2339 -96.071944 90)
		(property "Reference" "R487"
			(at 0 0 90)
			(layer "F.SilkS")
			(hide yes)
			(effects
				(font
					(size 1.27 1.27)
				)
			)
		)
		(property "Value" "0R2J-2-GP"
			(at 0.064008 -3.993896 90)
			(unlocked yes)
			(layer "F.Fab")
			(hide yes)
			(effects
				(font
					(size 1.016 1.016)
					(thickness 0.1524)
				)
			)
		)
		(property "Device Type" "R402H16"
			(at 0.064008 -5.517896 90)
			(unlocked yes)
			(layer "F.Fab")
			(hide yes)
			(effects
				(font
					(size 1.016 1.016)
					(thickness 0.1524)
				)
			)
		)
		(duplicate_pad_numbers_are_jumpers no)
		(fp_line
			(start 0.508 -0.9398)
			(end -0.508 -0.9398)
			(stroke
				(width 0.1524)
				(type default)
			)
			(layer "F.SilkS")
		)
		(fp_line
			(start -0.508 -0.9398)
			(end -0.508 0.9398)
			(stroke
				(width 0.1524)
				(type default)
			)
			(layer "F.SilkS")
		)
		(fp_rect
			(start -0.508 0.9398)
			(end 0.508 -0.9398)
			(stroke
				(width 0)
				(type default)
			)
			(fill no)
			(layer "F.CrtYd")
		)
		(fp_rect
			(start -0.508 0.9398)
			(end 0.508 -0.9398)
			(stroke
				(width 0)
				(type default)
			)
			(fill no)
			(layer "F.Fab")
		)
		(pad "1" smd custom
			(at 0 -0.4445 90)
			(size 0.1397 0.1397)
			(layers "F.Cu" "F.Mask" "F.Paste")
			(net "I2C_C_BUF_SDAIN")
			(options
				(clearance outline)
				(anchor circle)
			)
			(primitives
				(gr_poly
					(pts
						(arc
							(start -0.1778 -0.2794)
							(mid -0.249642 -0.249642)
							(end -0.2794 -0.1778)
						)
						(arc
							(start -0.2794 0.1778)
							(mid -0.249642 0.249642)
							(end -0.1778 0.2794)
						)
						(arc
							(start 0.1778 0.2794)
							(mid 0.249642 0.249642)
							(end 0.2794 0.1778)
						)
						(arc
							(start 0.2794 -0.1778)
							(mid 0.249642 -0.249642)
							(end 0.1778 -0.2794)
						)
					)
					(width 0)
					(fill yes)
				)
			)
		)
		(pad "2" smd custom
			(at 0 0.4445 90)
			(size 0.1397 0.1397)
			(layers "F.Cu" "F.Mask" "F.Paste")
			(net "I2C_C_BUF_SDA")
			(options
				(clearance outline)
				(anchor circle)
			)
			(primitives
				(gr_poly
					(pts
						(arc
							(start -0.1778 -0.2794)
							(mid -0.249642 -0.249642)
							(end -0.2794 -0.1778)
						)
						(arc
							(start -0.2794 0.1778)
							(mid -0.249642 0.249642)
							(end -0.1778 0.2794)
						)
						(arc
							(start 0.1778 0.2794)
							(mid 0.249642 0.249642)
							(end 0.2794 0.1778)
						)
						(arc
							(start 0.2794 -0.1778)
							(mid 0.249642 -0.249642)
							(end 0.1778 -0.2794)
						)
					)
					(width 0)
					(fill yes)
				)
			)
		)
	)
	(footprint ""
		(layer "F.Cu")
		(at 17.233138 -94.990666 90)
		(property "Reference" "R481"
			(at 0 0 90)
			(layer "F.SilkS")
			(hide yes)
			(effects
				(font
					(size 1.27 1.27)
				)
			)
		)
		(property "Value" "0R2J-2-GP"
			(at 0.064008 -3.993896 90)
			(unlocked yes)
			(layer "F.Fab")
			(hide yes)
			(effects
				(font
					(size 1.016 1.016)
					(thickness 0.1524)
				)
			)
		)
		(property "Device Type" "R402H16"
			(at 0.064008 -5.517896 90)
			(unlocked yes)
			(layer "F.Fab")
			(hide yes)
			(effects
				(font
					(size 1.016 1.016)
					(thickness 0.1524)
				)
			)
		)
		(duplicate_pad_numbers_are_jumpers no)
		(fp_line
			(start 0.508 -0.9398)
			(end -0.508 -0.9398)
			(stroke
				(width 0.1524)
				(type default)
			)
			(layer "F.SilkS")
		)
		(fp_line
			(start -0.508 -0.9398)
			(end -0.508 0.9398)
			(stroke
				(width 0.1524)
				(type default)
			)
			(layer "F.SilkS")
		)
		(fp_rect
			(start -0.508 0.9398)
			(end 0.508 -0.9398)
			(stroke
				(width 0)
				(type default)
			)
			(fill no)
			(layer "F.CrtYd")
		)
		(fp_rect
			(start -0.508 0.9398)
			(end 0.508 -0.9398)
			(stroke
				(width 0)
				(type default)
			)
			(fill no)
			(layer "F.Fab")
		)
		(pad "1" smd custom
			(at 0 -0.4445 90)
			(size 0.1397 0.1397)
			(layers "F.Cu" "F.Mask" "F.Paste")
			(net "I2C_C_SDA")
			(options
				(clearance outline)
				(anchor circle)
			)
			(primitives
				(gr_poly
					(pts
						(arc
							(start -0.1778 -0.2794)
							(mid -0.249642 -0.249642)
							(end -0.2794 -0.1778)
						)
						(arc
							(start -0.2794 0.1778)
							(mid -0.249642 0.249642)
							(end -0.1778 0.2794)
						)
						(arc
							(start 0.1778 0.2794)
							(mid 0.249642 0.249642)
							(end 0.2794 0.1778)
						)
						(arc
							(start 0.2794 -0.1778)
							(mid 0.249642 -0.249642)
							(end 0.1778 -0.2794)
						)
					)
					(width 0)
					(fill yes)
				)
			)
		)
		(pad "2" smd custom
			(at 0 0.4445 90)
			(size 0.1397 0.1397)
			(layers "F.Cu" "F.Mask" "F.Paste")
			(net "I2C_C_BUF_SDA")
			(options
				(clearance outline)
				(anchor circle)
			)
			(primitives
				(gr_poly
					(pts
						(arc
							(start -0.1778 -0.2794)
							(mid -0.249642 -0.249642)
							(end -0.2794 -0.1778)
						)
						(arc
							(start -0.2794 0.1778)
							(mid -0.249642 0.249642)
							(end -0.1778 0.2794)
						)
						(arc
							(start 0.1778 0.2794)
							(mid 0.249642 0.249642)
							(end 0.2794 0.1778)
						)
						(arc
							(start 0.2794 -0.1778)
							(mid 0.249642 -0.249642)
							(end 0.1778 -0.2794)
						)
					)
					(width 0)
					(fill yes)
				)
			)
		)
	)
	(footprint ""
		(layer "F.Cu")
		(at 117.348 -47.371 180)
		(property "Reference" "C361"
			(at 0 0 180)
			(layer "F.SilkS")
			(hide yes)
			(effects
				(font
					(size 1.27 1.27)
				)
			)
		)
		(property "Value" "SC47U16V0MX-GP"
			(at -0.00254 -4.78536 180)
			(unlocked yes)
			(layer "F.Fab")
			(hide yes)
			(effects
				(font
					(size 1.016 1.016)
					(thickness 0.1524)
				)
			)
		)
		(property "Device Type" "C1210H107"
			(at -0.00254 -6.38048 180)
			(unlocked yes)
			(layer "F.Fab")
			(hide yes)
			(effects
				(font
					(size 1.016 1.016)
					(thickness 0.1524)
				)
			)
		)
		(duplicate_pad_numbers_are_jumpers no)
		(fp_line
			(start 1.5748 2.3368)
			(end 1.5748 0.762)
			(stroke
				(width 0.1524)
				(type default)
			)
			(layer "F.SilkS")
		)
		(fp_line
			(start 1.5748 -0.762)
			(end 1.5748 -2.3368)
			(stroke
				(width 0.1524)
				(type default)
			)
			(layer "F.SilkS")
		)
		(fp_line
			(start 1.5748 -2.3368)
			(end -1.5748 -2.3368)
			(stroke
				(width 0.1524)
				(type default)
			)
			(layer "F.SilkS")
		)
		(fp_line
			(start -1.5748 2.3368)
			(end 1.5748 2.3368)
			(stroke
				(width 0.1524)
				(type default)
			)
			(layer "F.SilkS")
		)
		(fp_line
			(start -1.5748 0.762)
			(end -1.5748 2.3368)
			(stroke
				(width 0.1524)
				(type default)
			)
			(layer "F.SilkS")
		)
		(fp_line
			(start -1.5748 -2.3368)
			(end -1.5748 -0.762)
			(stroke
				(width 0.1524)
				(type default)
			)
			(layer "F.SilkS")
		)
		(fp_rect
			(start -1.651 2.413)
			(end 1.651 -2.413)
			(stroke
				(width 0)
				(type default)
			)
			(fill no)
			(layer "F.CrtYd")
		)
		(fp_poly
			(pts
				(xy 1.651 2.413) (xy 1.651 -2.413) (xy -1.651 -2.413) (xy -1.651 2.413)
			)
			(stroke
				(width 0)
				(type default)
			)
			(fill no)
			(layer "F.Fab")
		)
		(pad "1" smd rect
			(at 0 -1.4732 180)
			(size 2.794 1.397)
			(layers "F.Cu" "F.Mask" "F.Paste")
			(net "P12V")
		)
		(pad "2" smd rect
			(at 0 1.4732 180)
			(size 2.794 1.397)
			(layers "F.Cu" "F.Mask" "F.Paste")
			(net "GND")
		)
	)
	(footprint ""
		(layer "F.Cu")
		(at 14.059408 -98.824796)
		(property "Reference" "R370"
			(at 0 0 0)
			(layer "F.SilkS")
			(hide yes)
			(effects
				(font
					(size 1.27 1.27)
				)
			)
		)
		(property "Value" "4K7R2J-2-GP"
			(at 0.064008 -3.993896 0)
			(unlocked yes)
			(layer "F.Fab")
			(hide yes)
			(effects
				(font
					(size 1.016 1.016)
					(thickness 0.1524)
				)
			)
		)
		(property "Device Type" "R402H16"
			(at 0.064008 -5.517896 0)
			(unlocked yes)
			(layer "F.Fab")
			(hide yes)
			(effects
				(font
					(size 1.016 1.016)
					(thickness 0.1524)
				)
			)
		)
		(duplicate_pad_numbers_are_jumpers no)
		(fp_line
			(start -0.508 -0.9398)
			(end -0.508 0.9398)
			(stroke
				(width 0.1524)
				(type default)
			)
			(layer "F.SilkS")
		)
		(fp_line
			(start 0.508 -0.9398)
			(end -0.508 -0.9398)
			(stroke
				(width 0.1524)
				(type default)
			)
			(layer "F.SilkS")
		)
		(fp_rect
			(start -0.508 0.9398)
			(end 0.508 -0.9398)
			(stroke
				(width 0)
				(type default)
			)
			(fill no)
			(layer "F.CrtYd")
		)
		(fp_rect
			(start -0.508 0.9398)
			(end 0.508 -0.9398)
			(stroke
				(width 0)
				(type default)
			)
			(fill no)
			(layer "F.Fab")
		)
		(pad "1" smd custom
			(at 0 -0.4445)
			(size 0.1397 0.1397)
			(layers "F.Cu" "F.Mask" "F.Paste")
			(net "P3V3")
			(options
				(clearance outline)
				(anchor circle)
			)
			(primitives
				(gr_poly
					(pts
						(arc
							(start -0.1778 -0.2794)
							(mid -0.249642 -0.249642)
							(end -0.2794 -0.1778)
						)
						(arc
							(start -0.2794 0.1778)
							(mid -0.249642 0.249642)
							(end -0.1778 0.2794)
						)
						(arc
							(start 0.1778 0.2794)
							(mid 0.249642 0.249642)
							(end 0.2794 0.1778)
						)
						(arc
							(start 0.2794 -0.1778)
							(mid 0.249642 -0.249642)
							(end 0.1778 -0.2794)
						)
					)
					(width 0)
					(fill yes)
				)
			)
		)
		(pad "2" smd custom
			(at 0 0.4445)
			(size 0.1397 0.1397)
			(layers "F.Cu" "F.Mask" "F.Paste")
			(net "I2C_C_BUF_SDAIN")
			(options
				(clearance outline)
				(anchor circle)
			)
			(primitives
				(gr_poly
					(pts
						(arc
							(start -0.1778 -0.2794)
							(mid -0.249642 -0.249642)
							(end -0.2794 -0.1778)
						)
						(arc
							(start -0.2794 0.1778)
							(mid -0.249642 0.249642)
							(end -0.1778 0.2794)
						)
						(arc
							(start 0.1778 0.2794)
							(mid 0.249642 0.249642)
							(end 0.2794 0.1778)
						)
						(arc
							(start 0.2794 -0.1778)
							(mid 0.249642 -0.249642)
							(end 0.1778 -0.2794)
						)
					)
					(width 0)
					(fill yes)
				)
			)
		)
	)
	(footprint ""
		(layer "F.Cu")
		(at 0.050038 -49.179226 180)
		(property "Reference" "C348"
			(at 0 0 180)
			(layer "F.SilkS")
			(hide yes)
			(effects
				(font
					(size 1.27 1.27)
				)
			)
		)
		(property "Value" "SC10U25V5KX-GP"
			(at -0.0762 -6.1214 180)
			(unlocked yes)
			(layer "F.Fab")
			(hide yes)
			(effects
				(font
					(size 1.016 1.016)
					(thickness 0.1524)
				)
			)
		)
		(property "Device Type" "C805H56"
			(at -0.0762 -8.1534 180)
			(unlocked yes)
			(layer "F.Fab")
			(hide yes)
			(effects
				(font
					(size 1.016 1.016)
					(thickness 0.1524)
				)
			)
		)
		(duplicate_pad_numbers_are_jumpers no)
		(fp_line
			(start 0.635 0)
			(end -0.635 0)
			(stroke
				(width 0.508)
				(type default)
			)
			(layer "F.SilkS")
		)
		(fp_rect
			(start -0.9652 1.778)
			(end 0.9652 -1.778)
			(stroke
				(width 0)
				(type default)
			)
			(fill no)
			(layer "F.CrtYd")
		)
		(fp_poly
			(pts
				(xy -0.9652 -1.778) (xy 0.9652 -1.778) (xy 0.9652 1.778) (xy -0.9652 1.778)
			)
			(stroke
				(width 0)
				(type default)
			)
			(fill no)
			(layer "F.Fab")
		)
		(pad "1" smd rect
			(at 0 -0.9652 180)
			(size 1.397 1.143)
			(layers "F.Cu" "F.Mask" "F.Paste")
			(net "P12V")
		)
		(pad "2" smd rect
			(at 0 0.9652 180)
			(size 1.397 1.143)
			(layers "F.Cu" "F.Mask" "F.Paste")
			(net "GND")
		)
	)
)
